(kicad_pcb
	(version 20260206)
	(generator "pcbnew")
	(generator_version "10.0")
	(general
		(thickness 1.6)
		(legacy_teardrops no)
	)
	(paper "A4")
	(title_block
		(title "12092022_DA0F0TMDCD0_F0T_Management_Board_D_brd_V3_OCP.brd")
		(comment 1 "Grand Teton / footprints 497-502 of 1440")
	)
	(layers
		(0 "F.Cu" signal "TOP")
		(4 "In1.Cu" signal "GND")
		(6 "In2.Cu" signal "IN1")
		(8 "In3.Cu" signal "GND1")
		(10 "In4.Cu" signal "IN2")
		(12 "In5.Cu" signal "VCC")
		(14 "In6.Cu" signal "VCC1")
		(16 "In7.Cu" signal "IN3")
		(18 "In8.Cu" signal "GND2")
		(20 "In9.Cu" signal "IN4")
		(22 "In10.Cu" signal "GND3")
		(2 "B.Cu" signal "BOTTOM")
		(9 "F.Adhes" user "F.Adhesive")
		(11 "B.Adhes" user "B.Adhesive")
		(13 "F.Paste" user "Package Geometry/Pastemask Top")
		(15 "B.Paste" user "Package Geometry/Pastemask Bottom")
		(5 "F.SilkS" user "Ref Des/Silkscreen Top")
		(7 "B.SilkS" user "Ref Des/Silkscreen Bottom")
		(1 "F.Mask" user "Board Geometry/Soldermask Top")
		(3 "B.Mask" user "Board Geometry/Soldermask Bottom")
		(17 "Dwgs.User" user "User.Drawings")
		(19 "Cmts.User" user "User.Comments")
		(21 "Eco1.User" user "User.Eco1")
		(23 "Eco2.User" user "User.Eco2")
		(25 "Edge.Cuts" user "Board Geometry/Outline")
		(27 "Margin" user)
		(31 "F.CrtYd" user "Package Geometry/Place Bound Top")
		(29 "B.CrtYd" user "Package Geometry/Place Bound Bottom")
		(35 "F.Fab" user "Ref Des/Assembly Top")
		(33 "B.Fab" user "Ref Des/Assembly Bottom")
	)
	(footprint ""
		(layer "F.Cu")
		(at 11.171936 -53.518054)
		(property "Reference" "PR245"
			(at 0 0 0)
			(layer "F.SilkS")
			(hide yes)
			(effects
				(font
					(size 1.27 1.27)
				)
			)
		)
		(property "Value" ""
			(at 0 0 0)
			(layer "F.Fab")
			(effects
				(font
					(size 1.27 1.27)
				)
			)
		)
		(duplicate_pad_numbers_are_jumpers no)
		(fp_line
			(start -0.7874 -0.4064)
			(end 0.7874 -0.4064)
			(stroke
				(width 0.1524)
				(type default)
			)
			(layer "F.SilkS")
		)
		(fp_line
			(start -0.7874 0.4064)
			(end -0.7874 -0.4064)
			(stroke
				(width 0.1524)
				(type default)
			)
			(layer "F.SilkS")
		)
		(fp_line
			(start 0.7874 -0.4064)
			(end 0.7874 0.4064)
			(stroke
				(width 0.1524)
				(type default)
			)
			(layer "F.SilkS")
		)
		(fp_line
			(start 0.7874 0.4064)
			(end -0.7874 0.4064)
			(stroke
				(width 0.1524)
				(type default)
			)
			(layer "F.SilkS")
		)
		(fp_line
			(start -0.67945 -0.305054)
			(end -0.12065 -0.305054)
			(stroke
				(width 0.1)
				(type default)
			)
			(layer "F.Fab")
		)
		(fp_line
			(start -0.67945 0.3048)
			(end -0.67945 -0.305054)
			(stroke
				(width 0.1)
				(type default)
			)
			(layer "F.Fab")
		)
		(fp_line
			(start -0.12065 -0.305054)
			(end -0.12065 -0.2794)
			(stroke
				(width 0.1)
				(type default)
			)
			(layer "F.Fab")
		)
		(fp_line
			(start -0.12065 -0.2794)
			(end 0.12065 -0.2794)
			(stroke
				(width 0.1)
				(type default)
			)
			(layer "F.Fab")
		)
		(fp_line
			(start -0.12065 0.2794)
			(end -0.12065 0.3048)
			(stroke
				(width 0.1)
				(type default)
			)
			(layer "F.Fab")
		)
		(fp_line
			(start -0.12065 0.3048)
			(end -0.67945 0.3048)
			(stroke
				(width 0.1)
				(type default)
			)
			(layer "F.Fab")
		)
		(fp_line
			(start 0.120396 0.2794)
			(end -0.12065 0.2794)
			(stroke
				(width 0.1)
				(type default)
			)
			(layer "F.Fab")
		)
		(fp_line
			(start 0.120396 0.3048)
			(end 0.120396 0.2794)
			(stroke
				(width 0.1)
				(type default)
			)
			(layer "F.Fab")
		)
		(fp_line
			(start 0.12065 -0.3048)
			(end 0.67945 -0.3048)
			(stroke
				(width 0.1)
				(type default)
			)
			(layer "F.Fab")
		)
		(fp_line
			(start 0.12065 -0.2794)
			(end 0.12065 -0.3048)
			(stroke
				(width 0.1)
				(type default)
			)
			(layer "F.Fab")
		)
		(fp_line
			(start 0.67945 -0.3048)
			(end 0.67945 0.3048)
			(stroke
				(width 0.1)
				(type default)
			)
			(layer "F.Fab")
		)
		(fp_line
			(start 0.67945 0.3048)
			(end 0.120396 0.3048)
			(stroke
				(width 0.1)
				(type default)
			)
			(layer "F.Fab")
		)
		(pad "1" smd circle
			(at -0.40005 0)
			(size 0 0)
			(layers "F.Cu" "F.Mask" "F.Paste")
			(net "PWRGD_P5V_AUX_R")
		)
		(pad "2" smd circle
			(at 0.40005 0)
			(size 0 0)
			(layers "F.Cu" "F.Mask" "F.Paste")
			(net "GND")
		)
	)
	(footprint ""
		(layer "F.Cu")
		(at 76.981558 -74.476356 90)
		(property "Reference" "R620"
			(at 0 0 90)
			(layer "F.SilkS")
			(hide yes)
			(effects
				(font
					(size 1.27 1.27)
				)
			)
		)
		(property "Value" ""
			(at 0 0 90)
			(layer "F.Fab")
			(effects
				(font
					(size 1.27 1.27)
				)
			)
		)
		(duplicate_pad_numbers_are_jumpers no)
		(fp_line
			(start 0.7874 -0.4064)
			(end 0.7874 0.4064)
			(stroke
				(width 0.1524)
				(type default)
			)
			(layer "F.SilkS")
		)
		(fp_line
			(start -0.7874 -0.4064)
			(end 0.7874 -0.4064)
			(stroke
				(width 0.1524)
				(type default)
			)
			(layer "F.SilkS")
		)
		(fp_line
			(start 0.7874 0.4064)
			(end -0.7874 0.4064)
			(stroke
				(width 0.1524)
				(type default)
			)
			(layer "F.SilkS")
		)
		(fp_line
			(start -0.7874 0.4064)
			(end -0.7874 -0.4064)
			(stroke
				(width 0.1524)
				(type default)
			)
			(layer "F.SilkS")
		)
		(fp_line
			(start -0.12065 -0.305054)
			(end -0.12065 -0.2794)
			(stroke
				(width 0.1)
				(type default)
			)
			(layer "F.Fab")
		)
		(fp_line
			(start -0.67945 -0.305054)
			(end -0.12065 -0.305054)
			(stroke
				(width 0.1)
				(type default)
			)
			(layer "F.Fab")
		)
		(fp_line
			(start 0.67945 -0.3048)
			(end 0.67945 0.3048)
			(stroke
				(width 0.1)
				(type default)
			)
			(layer "F.Fab")
		)
		(fp_line
			(start 0.12065 -0.3048)
			(end 0.67945 -0.3048)
			(stroke
				(width 0.1)
				(type default)
			)
			(layer "F.Fab")
		)
		(fp_line
			(start 0.12065 -0.2794)
			(end 0.12065 -0.3048)
			(stroke
				(width 0.1)
				(type default)
			)
			(layer "F.Fab")
		)
		(fp_line
			(start -0.12065 -0.2794)
			(end 0.12065 -0.2794)
			(stroke
				(width 0.1)
				(type default)
			)
			(layer "F.Fab")
		)
		(fp_line
			(start 0.120396 0.2794)
			(end -0.12065 0.2794)
			(stroke
				(width 0.1)
				(type default)
			)
			(layer "F.Fab")
		)
		(fp_line
			(start -0.12065 0.2794)
			(end -0.12065 0.3048)
			(stroke
				(width 0.1)
				(type default)
			)
			(layer "F.Fab")
		)
		(fp_line
			(start 0.67945 0.3048)
			(end 0.120396 0.3048)
			(stroke
				(width 0.1)
				(type default)
			)
			(layer "F.Fab")
		)
		(fp_line
			(start 0.120396 0.3048)
			(end 0.120396 0.2794)
			(stroke
				(width 0.1)
				(type default)
			)
			(layer "F.Fab")
		)
		(fp_line
			(start -0.12065 0.3048)
			(end -0.67945 0.3048)
			(stroke
				(width 0.1)
				(type default)
			)
			(layer "F.Fab")
		)
		(fp_line
			(start -0.67945 0.3048)
			(end -0.67945 -0.305054)
			(stroke
				(width 0.1)
				(type default)
			)
			(layer "F.Fab")
		)
		(pad "1" smd circle
			(at -0.40005 0 90)
			(size 0 0)
			(layers "F.Cu" "F.Mask" "F.Paste")
			(net "FM_JTAG_TCK_MUX_BMC_SEL")
		)
		(pad "2" smd circle
			(at 0.40005 0 90)
			(size 0 0)
			(layers "F.Cu" "F.Mask" "F.Paste")
			(net "GND")
		)
	)
	(footprint ""
		(layer "F.Cu")
		(at 28.1432 -65.7098 90)
		(property "Reference" "R67"
			(at 0 0 90)
			(layer "F.SilkS")
			(hide yes)
			(effects
				(font
					(size 1.27 1.27)
				)
			)
		)
		(property "Value" ""
			(at 0 0 90)
			(layer "F.Fab")
			(effects
				(font
					(size 1.27 1.27)
				)
			)
		)
		(duplicate_pad_numbers_are_jumpers no)
		(fp_line
			(start 0.7874 -0.4064)
			(end 0.7874 0.4064)
			(stroke
				(width 0.1524)
				(type default)
			)
			(layer "F.SilkS")
		)
		(fp_line
			(start -0.7874 -0.4064)
			(end 0.7874 -0.4064)
			(stroke
				(width 0.1524)
				(type default)
			)
			(layer "F.SilkS")
		)
		(fp_line
			(start 0.7874 0.4064)
			(end -0.7874 0.4064)
			(stroke
				(width 0.1524)
				(type default)
			)
			(layer "F.SilkS")
		)
		(fp_line
			(start -0.7874 0.4064)
			(end -0.7874 -0.4064)
			(stroke
				(width 0.1524)
				(type default)
			)
			(layer "F.SilkS")
		)
		(fp_line
			(start -0.12065 -0.305054)
			(end -0.12065 -0.2794)
			(stroke
				(width 0.1)
				(type default)
			)
			(layer "F.Fab")
		)
		(fp_line
			(start -0.67945 -0.305054)
			(end -0.12065 -0.305054)
			(stroke
				(width 0.1)
				(type default)
			)
			(layer "F.Fab")
		)
		(fp_line
			(start 0.67945 -0.3048)
			(end 0.67945 0.3048)
			(stroke
				(width 0.1)
				(type default)
			)
			(layer "F.Fab")
		)
		(fp_line
			(start 0.12065 -0.3048)
			(end 0.67945 -0.3048)
			(stroke
				(width 0.1)
				(type default)
			)
			(layer "F.Fab")
		)
		(fp_line
			(start 0.12065 -0.2794)
			(end 0.12065 -0.3048)
			(stroke
				(width 0.1)
				(type default)
			)
			(layer "F.Fab")
		)
		(fp_line
			(start -0.12065 -0.2794)
			(end 0.12065 -0.2794)
			(stroke
				(width 0.1)
				(type default)
			)
			(layer "F.Fab")
		)
		(fp_line
			(start 0.120396 0.2794)
			(end -0.12065 0.2794)
			(stroke
				(width 0.1)
				(type default)
			)
			(layer "F.Fab")
		)
		(fp_line
			(start -0.12065 0.2794)
			(end -0.12065 0.3048)
			(stroke
				(width 0.1)
				(type default)
			)
			(layer "F.Fab")
		)
		(fp_line
			(start 0.67945 0.3048)
			(end 0.120396 0.3048)
			(stroke
				(width 0.1)
				(type default)
			)
			(layer "F.Fab")
		)
		(fp_line
			(start 0.120396 0.3048)
			(end 0.120396 0.2794)
			(stroke
				(width 0.1)
				(type default)
			)
			(layer "F.Fab")
		)
		(fp_line
			(start -0.12065 0.3048)
			(end -0.67945 0.3048)
			(stroke
				(width 0.1)
				(type default)
			)
			(layer "F.Fab")
		)
		(fp_line
			(start -0.67945 0.3048)
			(end -0.67945 -0.305054)
			(stroke
				(width 0.1)
				(type default)
			)
			(layer "F.Fab")
		)
		(pad "1" smd circle
			(at -0.40005 0 90)
			(size 0 0)
			(layers "F.Cu" "F.Mask" "F.Paste")
			(net "P3V3_AUX")
		)
		(pad "2" smd circle
			(at 0.40005 0 90)
			(size 0 0)
			(layers "F.Cu" "F.Mask" "F.Paste")
			(net "UART_BMC_5_TXD_BUF1_R")
		)
	)
	(footprint ""
		(layer "F.Cu")
		(at 85.1662 -75.1586)
		(property "Reference" "C155"
			(at 0 0 0)
			(layer "F.SilkS")
			(hide yes)
			(effects
				(font
					(size 1.27 1.27)
				)
			)
		)
		(property "Value" ""
			(at 0 0 0)
			(layer "F.Fab")
			(effects
				(font
					(size 1.27 1.27)
				)
			)
		)
		(duplicate_pad_numbers_are_jumpers no)
		(fp_line
			(start -0.7874 -0.4064)
			(end 0.7874 -0.4064)
			(stroke
				(width 0.1524)
				(type default)
			)
			(layer "F.SilkS")
		)
		(fp_line
			(start -0.7874 0.4064)
			(end -0.7874 -0.4064)
			(stroke
				(width 0.1524)
				(type default)
			)
			(layer "F.SilkS")
		)
		(fp_line
			(start 0.7874 -0.4064)
			(end 0.7874 0.4064)
			(stroke
				(width 0.1524)
				(type default)
			)
			(layer "F.SilkS")
		)
		(fp_line
			(start 0.7874 0.4064)
			(end -0.7874 0.4064)
			(stroke
				(width 0.1524)
				(type default)
			)
			(layer "F.SilkS")
		)
		(fp_line
			(start -0.67945 -0.305054)
			(end -0.12065 -0.305054)
			(stroke
				(width 0.1)
				(type default)
			)
			(layer "F.Fab")
		)
		(fp_line
			(start -0.67945 0.3048)
			(end -0.67945 -0.305054)
			(stroke
				(width 0.1)
				(type default)
			)
			(layer "F.Fab")
		)
		(fp_line
			(start -0.12065 -0.305054)
			(end -0.12065 -0.2794)
			(stroke
				(width 0.1)
				(type default)
			)
			(layer "F.Fab")
		)
		(fp_line
			(start -0.12065 -0.2794)
			(end 0.12065 -0.2794)
			(stroke
				(width 0.1)
				(type default)
			)
			(layer "F.Fab")
		)
		(fp_line
			(start -0.12065 0.2794)
			(end -0.12065 0.3048)
			(stroke
				(width 0.1)
				(type default)
			)
			(layer "F.Fab")
		)
		(fp_line
			(start -0.12065 0.3048)
			(end -0.67945 0.3048)
			(stroke
				(width 0.1)
				(type default)
			)
			(layer "F.Fab")
		)
		(fp_line
			(start 0.120396 0.2794)
			(end -0.12065 0.2794)
			(stroke
				(width 0.1)
				(type default)
			)
			(layer "F.Fab")
		)
		(fp_line
			(start 0.120396 0.3048)
			(end 0.120396 0.2794)
			(stroke
				(width 0.1)
				(type default)
			)
			(layer "F.Fab")
		)
		(fp_line
			(start 0.12065 -0.3048)
			(end 0.67945 -0.3048)
			(stroke
				(width 0.1)
				(type default)
			)
			(layer "F.Fab")
		)
		(fp_line
			(start 0.12065 -0.2794)
			(end 0.12065 -0.3048)
			(stroke
				(width 0.1)
				(type default)
			)
			(layer "F.Fab")
		)
		(fp_line
			(start 0.67945 -0.3048)
			(end 0.67945 0.3048)
			(stroke
				(width 0.1)
				(type default)
			)
			(layer "F.Fab")
		)
		(fp_line
			(start 0.67945 0.3048)
			(end 0.120396 0.3048)
			(stroke
				(width 0.1)
				(type default)
			)
			(layer "F.Fab")
		)
		(pad "1" smd circle
			(at -0.40005 0)
			(size 0 0)
			(layers "F.Cu" "F.Mask" "F.Paste")
			(net "PWRGD_P1V2_AUX_R")
		)
		(pad "2" smd circle
			(at 0.40005 0)
			(size 0 0)
			(layers "F.Cu" "F.Mask" "F.Paste")
			(net "GND")
		)
	)
	(footprint ""
		(layer "F.Cu")
		(at 49.80051 -30.867604 90)
		(property "Reference" "R249"
			(at 0 0 90)
			(layer "F.SilkS")
			(hide yes)
			(effects
				(font
					(size 1.27 1.27)
				)
			)
		)
		(property "Value" ""
			(at 0 0 90)
			(layer "F.Fab")
			(effects
				(font
					(size 1.27 1.27)
				)
			)
		)
		(duplicate_pad_numbers_are_jumpers no)
		(fp_line
			(start 0.7874 -0.4064)
			(end 0.7874 0.4064)
			(stroke
				(width 0.1524)
				(type default)
			)
			(layer "F.SilkS")
		)
		(fp_line
			(start -0.7874 -0.4064)
			(end 0.7874 -0.4064)
			(stroke
				(width 0.1524)
				(type default)
			)
			(layer "F.SilkS")
		)
		(fp_line
			(start 0.7874 0.4064)
			(end -0.7874 0.4064)
			(stroke
				(width 0.1524)
				(type default)
			)
			(layer "F.SilkS")
		)
		(fp_line
			(start -0.7874 0.4064)
			(end -0.7874 -0.4064)
			(stroke
				(width 0.1524)
				(type default)
			)
			(layer "F.SilkS")
		)
		(fp_line
			(start -0.12065 -0.305054)
			(end -0.12065 -0.2794)
			(stroke
				(width 0.1)
				(type default)
			)
			(layer "F.Fab")
		)
		(fp_line
			(start -0.67945 -0.305054)
			(end -0.12065 -0.305054)
			(stroke
				(width 0.1)
				(type default)
			)
			(layer "F.Fab")
		)
		(fp_line
			(start 0.67945 -0.3048)
			(end 0.67945 0.3048)
			(stroke
				(width 0.1)
				(type default)
			)
			(layer "F.Fab")
		)
		(fp_line
			(start 0.12065 -0.3048)
			(end 0.67945 -0.3048)
			(stroke
				(width 0.1)
				(type default)
			)
			(layer "F.Fab")
		)
		(fp_line
			(start 0.12065 -0.2794)
			(end 0.12065 -0.3048)
			(stroke
				(width 0.1)
				(type default)
			)
			(layer "F.Fab")
		)
		(fp_line
			(start -0.12065 -0.2794)
			(end 0.12065 -0.2794)
			(stroke
				(width 0.1)
				(type default)
			)
			(layer "F.Fab")
		)
		(fp_line
			(start 0.120396 0.2794)
			(end -0.12065 0.2794)
			(stroke
				(width 0.1)
				(type default)
			)
			(layer "F.Fab")
		)
		(fp_line
			(start -0.12065 0.2794)
			(end -0.12065 0.3048)
			(stroke
				(width 0.1)
				(type default)
			)
			(layer "F.Fab")
		)
		(fp_line
			(start 0.67945 0.3048)
			(end 0.120396 0.3048)
			(stroke
				(width 0.1)
				(type default)
			)
			(layer "F.Fab")
		)
		(fp_line
			(start 0.120396 0.3048)
			(end 0.120396 0.2794)
			(stroke
				(width 0.1)
				(type default)
			)
			(layer "F.Fab")
		)
		(fp_line
			(start -0.12065 0.3048)
			(end -0.67945 0.3048)
			(stroke
				(width 0.1)
				(type default)
			)
			(layer "F.Fab")
		)
		(fp_line
			(start -0.67945 0.3048)
			(end -0.67945 -0.305054)
			(stroke
				(width 0.1)
				(type default)
			)
			(layer "F.Fab")
		)
		(pad "1" smd circle
			(at -0.40005 0 90)
			(size 0 0)
			(layers "F.Cu" "F.Mask" "F.Paste")
			(net "P3V3_AUX")
		)
		(pad "2" smd circle
			(at 0.40005 0 90)
			(size 0 0)
			(layers "F.Cu" "F.Mask" "F.Paste")
			(net "SMB_BMC_MM3_SDA")
		)
	)
	(footprint ""
		(layer "F.Cu")
		(at 84.652612 -37.303456 90)
		(property "Reference" "C291"
			(at 0 0 90)
			(layer "F.SilkS")
			(hide yes)
			(effects
				(font
					(size 1.27 1.27)
				)
			)
		)
		(property "Value" ""
			(at 0 0 90)
			(layer "F.Fab")
			(effects
				(font
					(size 1.27 1.27)
				)
			)
		)
		(duplicate_pad_numbers_are_jumpers no)
		(fp_line
			(start 0.7874 -0.4064)
			(end 0.7874 0.4064)
			(stroke
				(width 0.1524)
				(type default)
			)
			(layer "F.SilkS")
		)
		(fp_line
			(start -0.7874 -0.4064)
			(end 0.7874 -0.4064)
			(stroke
				(width 0.1524)
				(type default)
			)
			(layer "F.SilkS")
		)
		(fp_line
			(start 0.7874 0.4064)
			(end -0.7874 0.4064)
			(stroke
				(width 0.1524)
				(type default)
			)
			(layer "F.SilkS")
		)
		(fp_line
			(start -0.7874 0.4064)
			(end -0.7874 -0.4064)
			(stroke
				(width 0.1524)
				(type default)
			)
			(layer "F.SilkS")
		)
		(fp_line
			(start -0.12065 -0.305054)
			(end -0.12065 -0.2794)
			(stroke
				(width 0.1)
				(type default)
			)
			(layer "F.Fab")
		)
		(fp_line
			(start -0.67945 -0.305054)
			(end -0.12065 -0.305054)
			(stroke
				(width 0.1)
				(type default)
			)
			(layer "F.Fab")
		)
		(fp_line
			(start 0.67945 -0.3048)
			(end 0.67945 0.3048)
			(stroke
				(width 0.1)
				(type default)
			)
			(layer "F.Fab")
		)
		(fp_line
			(start 0.12065 -0.3048)
			(end 0.67945 -0.3048)
			(stroke
				(width 0.1)
				(type default)
			)
			(layer "F.Fab")
		)
		(fp_line
			(start 0.12065 -0.2794)
			(end 0.12065 -0.3048)
			(stroke
				(width 0.1)
				(type default)
			)
			(layer "F.Fab")
		)
		(fp_line
			(start -0.12065 -0.2794)
			(end 0.12065 -0.2794)
			(stroke
				(width 0.1)
				(type default)
			)
			(layer "F.Fab")
		)
		(fp_line
			(start 0.120396 0.2794)
			(end -0.12065 0.2794)
			(stroke
				(width 0.1)
				(type default)
			)
			(layer "F.Fab")
		)
		(fp_line
			(start -0.12065 0.2794)
			(end -0.12065 0.3048)
			(stroke
				(width 0.1)
				(type default)
			)
			(layer "F.Fab")
		)
		(fp_line
			(start 0.67945 0.3048)
			(end 0.120396 0.3048)
			(stroke
				(width 0.1)
				(type default)
			)
			(layer "F.Fab")
		)
		(fp_line
			(start 0.120396 0.3048)
			(end 0.120396 0.2794)
			(stroke
				(width 0.1)
				(type default)
			)
			(layer "F.Fab")
		)
		(fp_line
			(start -0.12065 0.3048)
			(end -0.67945 0.3048)
			(stroke
				(width 0.1)
				(type default)
			)
			(layer "F.Fab")
		)
		(fp_line
			(start -0.67945 0.3048)
			(end -0.67945 -0.305054)
			(stroke
				(width 0.1)
				(type default)
			)
			(layer "F.Fab")
		)
		(pad "1" smd circle
			(at -0.40005 0 90)
			(size 0 0)
			(layers "F.Cu" "F.Mask" "F.Paste")
			(net "P2V5_AUX")
		)
		(pad "2" smd circle
			(at 0.40005 0 90)
			(size 0 0)
			(layers "F.Cu" "F.Mask" "F.Paste")
			(net "GND")
		)
	)
)
